# SCM (Grand Teton) — schematic netlist excerpt (pin names and nets, part order shuffled) for the footprints in the layout excerpt that follows; sources: Cadence DE-HDL packaged netlist, KiCad conversion of 12092022_DA0F0TMDCD0_F0T_Management_Board_D_brd_V3_OCP.brd

R274  Q_RES  100K 1% EMPTY  pkg 0402LF  page 29 : A = P3V3_AUX ; B = DEBUG_PORT_UART_RX
R816  Q_RES  4.7K 1% CHIP  pkg 0402LF  page 13 : A = P3V3_AUX ; B = IRQ_PCH_SCI_WHEA_N

(kicad_pcb
	(version 20260206)
	(generator "pcbnew")
	(generator_version "10.0")
	(general
		(thickness 1.6)
		(legacy_teardrops no)
	)
	(paper "A4")
	(title_block
		(title "12092022_DA0F0TMDCD0_F0T_Management_Board_D_brd_V3_OCP.brd")
		(comment 1 "Grand Teton / footprints 1316-1317 of 1440")
	)
	(layers
		(0 "F.Cu" signal "TOP")
		(4 "In1.Cu" signal "GND")
		(6 "In2.Cu" signal "IN1")
		(8 "In3.Cu" signal "GND1")
		(10 "In4.Cu" signal "IN2")
		(12 "In5.Cu" signal "VCC")
		(14 "In6.Cu" signal "VCC1")
		(16 "In7.Cu" signal "IN3")
		(18 "In8.Cu" signal "GND2")
		(20 "In9.Cu" signal "IN4")
		(22 "In10.Cu" signal "GND3")
		(2 "B.Cu" signal "BOTTOM")
		(9 "F.Adhes" user "F.Adhesive")
		(11 "B.Adhes" user "B.Adhesive")
		(13 "F.Paste" user "Package Geometry/Pastemask Top")
		(15 "B.Paste" user "Package Geometry/Pastemask Bottom")
		(5 "F.SilkS" user "Ref Des/Silkscreen Top")
		(7 "B.SilkS" user "Ref Des/Silkscreen Bottom")
		(1 "F.Mask" user "Board Geometry/Soldermask Top")
		(3 "B.Mask" user "Board Geometry/Soldermask Bottom")
		(17 "Dwgs.User" user "User.Drawings")
		(19 "Cmts.User" user "User.Comments")
		(21 "Eco1.User" user "User.Eco1")
		(23 "Eco2.User" user "User.Eco2")
		(25 "Edge.Cuts" user "Board Geometry/Outline")
		(27 "Margin" user)
		(31 "F.CrtYd" user "Package Geometry/Place Bound Top")
		(29 "B.CrtYd" user "Package Geometry/Place Bound Bottom")
		(35 "F.Fab" user "Ref Des/Assembly Top")
		(33 "B.Fab" user "Ref Des/Assembly Bottom")
	)
	(footprint ""
		(layer "B.Cu")
		(at 61.8744 -18.2626)
		(property "Reference" "R274"
			(at 0 0 0)
			(layer "B.SilkS")
			(hide yes)
			(effects
				(font
					(size 1.27 1.27)
				)
				(justify mirror)
			)
		)
		(property "Value" ""
			(at 0 0 0)
			(layer "B.Fab")
			(effects
				(font
					(size 1.27 1.27)
				)
				(justify mirror)
			)
		)
		(duplicate_pad_numbers_are_jumpers no)
		(fp_line
			(start -0.7874 -0.4064)
			(end -0.7874 0.4064)
			(stroke
				(width 0.1524)
				(type default)
			)
			(layer "B.SilkS")
		)
		(fp_line
			(start -0.7874 0.4064)
			(end 0.7874 0.4064)
			(stroke
				(width 0.1524)
				(type default)
			)
			(layer "B.SilkS")
		)
		(fp_line
			(start 0.7874 -0.4064)
			(end -0.7874 -0.4064)
			(stroke
				(width 0.1524)
				(type default)
			)
			(layer "B.SilkS")
		)
		(fp_line
			(start 0.7874 0.4064)
			(end 0.7874 -0.4064)
			(stroke
				(width 0.1524)
				(type default)
			)
			(layer "B.SilkS")
		)
		(fp_line
			(start -0.67945 -0.3048)
			(end -0.67945 0.3048)
			(stroke
				(width 0.1)
				(type default)
			)
			(layer "B.Fab")
		)
		(fp_line
			(start -0.67945 0.3048)
			(end -0.120396 0.3048)
			(stroke
				(width 0.1)
				(type default)
			)
			(layer "B.Fab")
		)
		(fp_line
			(start -0.12065 -0.3048)
			(end -0.67945 -0.3048)
			(stroke
				(width 0.1)
				(type default)
			)
			(layer "B.Fab")
		)
		(fp_line
			(start -0.12065 -0.2794)
			(end -0.12065 -0.3048)
			(stroke
				(width 0.1)
				(type default)
			)
			(layer "B.Fab")
		)
		(fp_line
			(start -0.120396 0.2794)
			(end 0.12065 0.2794)
			(stroke
				(width 0.1)
				(type default)
			)
			(layer "B.Fab")
		)
		(fp_line
			(start -0.120396 0.3048)
			(end -0.120396 0.2794)
			(stroke
				(width 0.1)
				(type default)
			)
			(layer "B.Fab")
		)
		(fp_line
			(start 0.12065 -0.305054)
			(end 0.12065 -0.2794)
			(stroke
				(width 0.1)
				(type default)
			)
			(layer "B.Fab")
		)
		(fp_line
			(start 0.12065 -0.2794)
			(end -0.12065 -0.2794)
			(stroke
				(width 0.1)
				(type default)
			)
			(layer "B.Fab")
		)
		(fp_line
			(start 0.12065 0.2794)
			(end 0.12065 0.3048)
			(stroke
				(width 0.1)
				(type default)
			)
			(layer "B.Fab")
		)
		(fp_line
			(start 0.12065 0.3048)
			(end 0.67945 0.3048)
			(stroke
				(width 0.1)
				(type default)
			)
			(layer "B.Fab")
		)
		(fp_line
			(start 0.67945 -0.305054)
			(end 0.12065 -0.305054)
			(stroke
				(width 0.1)
				(type default)
			)
			(layer "B.Fab")
		)
		(fp_line
			(start 0.67945 0.3048)
			(end 0.67945 -0.305054)
			(stroke
				(width 0.1)
				(type default)
			)
			(layer "B.Fab")
		)
		(pad "1" smd circle
			(at 0.40005 0 180)
			(size 0 0)
			(layers "B.Cu" "B.Mask" "B.Paste")
			(net "P3V3_AUX")
		)
		(pad "2" smd circle
			(at -0.40005 0 180)
			(size 0 0)
			(layers "B.Cu" "B.Mask" "B.Paste")
			(net "DEBUG_PORT_UART_RX")
		)
	)
	(footprint ""
		(layer "B.Cu")
		(at 52.7812 -30.861 -90)
		(property "Reference" "R816"
			(at 0 0 90)
			(layer "B.SilkS")
			(hide yes)
			(effects
				(font
					(size 1.27 1.27)
				)
				(justify mirror)
			)
		)
		(property "Value" ""
			(at 0 0 90)
			(layer "B.Fab")
			(effects
				(font
					(size 1.27 1.27)
				)
				(justify mirror)
			)
		)
		(duplicate_pad_numbers_are_jumpers no)
		(fp_line
			(start -0.7874 0.4064)
			(end 0.7874 0.4064)
			(stroke
				(width 0.1524)
				(type default)
			)
			(layer "B.SilkS")
		)
		(fp_line
			(start 0.7874 0.4064)
			(end 0.7874 -0.4064)
			(stroke
				(width 0.1524)
				(type default)
			)
			(layer "B.SilkS")
		)
		(fp_line
			(start -0.7874 -0.4064)
			(end -0.7874 0.4064)
			(stroke
				(width 0.1524)
				(type default)
			)
			(layer "B.SilkS")
		)
		(fp_line
			(start 0.7874 -0.4064)
			(end -0.7874 -0.4064)
			(stroke
				(width 0.1524)
				(type default)
			)
			(layer "B.SilkS")
		)
		(fp_line
			(start -0.67945 0.3048)
			(end -0.120396 0.3048)
			(stroke
				(width 0.1)
				(type default)
			)
			(layer "B.Fab")
		)
		(fp_line
			(start -0.120396 0.3048)
			(end -0.120396 0.2794)
			(stroke
				(width 0.1)
				(type default)
			)
			(layer "B.Fab")
		)
		(fp_line
			(start 0.12065 0.3048)
			(end 0.67945 0.3048)
			(stroke
				(width 0.1)
				(type default)
			)
			(layer "B.Fab")
		)
		(fp_line
			(start 0.67945 0.3048)
			(end 0.67945 -0.305054)
			(stroke
				(width 0.1)
				(type default)
			)
			(layer "B.Fab")
		)
		(fp_line
			(start -0.120396 0.2794)
			(end 0.12065 0.2794)
			(stroke
				(width 0.1)
				(type default)
			)
			(layer "B.Fab")
		)
		(fp_line
			(start 0.12065 0.2794)
			(end 0.12065 0.3048)
			(stroke
				(width 0.1)
				(type default)
			)
			(layer "B.Fab")
		)
		(fp_line
			(start -0.12065 -0.2794)
			(end -0.12065 -0.3048)
			(stroke
				(width 0.1)
				(type default)
			)
			(layer "B.Fab")
		)
		(fp_line
			(start 0.12065 -0.2794)
			(end -0.12065 -0.2794)
			(stroke
				(width 0.1)
				(type default)
			)
			(layer "B.Fab")
		)
		(fp_line
			(start -0.67945 -0.3048)
			(end -0.67945 0.3048)
			(stroke
				(width 0.1)
				(type default)
			)
			(layer "B.Fab")
		)
		(fp_line
			(start -0.12065 -0.3048)
			(end -0.67945 -0.3048)
			(stroke
				(width 0.1)
				(type default)
			)
			(layer "B.Fab")
		)
		(fp_line
			(start 0.12065 -0.305054)
			(end 0.12065 -0.2794)
			(stroke
				(width 0.1)
				(type default)
			)
			(layer "B.Fab")
		)
		(fp_line
			(start 0.67945 -0.305054)
			(end 0.12065 -0.305054)
			(stroke
				(width 0.1)
				(type default)
			)
			(layer "B.Fab")
		)
		(pad "1" smd circle
			(at 0.40005 0 90)
			(size 0 0)
			(layers "B.Cu" "B.Mask" "B.Paste")
			(net "P3V3_AUX")
		)
		(pad "2" smd circle
			(at -0.40005 0 90)
			(size 0 0)
			(layers "B.Cu" "B.Mask" "B.Paste")
			(net "IRQ_PCH_SCI_WHEA_N")
		)
	)
)
